# S9S_MB_2U (Grand Teton) — schematic netlist excerpt (pin names and nets, part order shuffled) for the footprints in the layout excerpt that follows; sources: Cadence DE-HDL packaged netlist, KiCad conversion of 03242023_DA0F0TMBIJ0_F0T_Motherboard_J_brd_V01_OCP.brd

R1689  Q_RES  6.19K 1% CHIP  pkg 0402LF  page 244 : A = FM_COMP_P3V3_AUX_VIN ; B = GND
C810  Q_CAP_DIFFBUS  DIFF BUS_0.22UF 6.3V 20% X6S  pkg C0201  page 175 : \1\ = P5E_CPU1_PE1_TX_C_DN<13> ; \2\ = P5E_CPU1_PE1_TX_DN<13>
R2316  Q_RES  0 5% CHIP  pkg 0402LF  page 258 : A = PWRGD_P5V_AUX_R ; B = PWRGD_P5V_AUX

(kicad_pcb
	(version 20260206)
	(generator "pcbnew")
	(generator_version "10.0")
	(general
		(thickness 1.6)
		(legacy_teardrops no)
	)
	(paper "A4")
	(title_block
		(title "03242023_DA0F0TMBIJ0_F0T_Motherboard_J_brd_V01_OCP.brd")
		(comment 1 "Grand Teton / footprints 3231-3233 of 6105")
	)
	(layers
		(0 "F.Cu" signal "TOP")
		(4 "In1.Cu" signal "GND")
		(6 "In2.Cu" signal "IN1")
		(8 "In3.Cu" signal "GND1")
		(10 "In4.Cu" signal "IN2")
		(12 "In5.Cu" signal "GND2")
		(14 "In6.Cu" signal "IN3")
		(16 "In7.Cu" signal "GND3")
		(18 "In8.Cu" signal "VCC")
		(20 "In9.Cu" signal "VCC1")
		(22 "In10.Cu" signal "GND4")
		(24 "In11.Cu" signal "IN4")
		(26 "In12.Cu" signal "GND5")
		(28 "In13.Cu" signal "IN5")
		(30 "In14.Cu" signal "GND6")
		(32 "In15.Cu" signal "IN6")
		(34 "In16.Cu" signal "GND7")
		(2 "B.Cu" signal "BOTTOM")
		(9 "F.Adhes" user "F.Adhesive")
		(11 "B.Adhes" user "B.Adhesive")
		(13 "F.Paste" user "Package Geometry/Pastemask Top")
		(15 "B.Paste" user "Package Geometry/Pastemask Bottom")
		(5 "F.SilkS" user "Ref Des/Silkscreen Top")
		(7 "B.SilkS" user "Ref Des/Silkscreen Bottom")
		(1 "F.Mask" user "Board Geometry/Soldermask Top")
		(3 "B.Mask" user "Board Geometry/Soldermask Bottom")
		(17 "Dwgs.User" user "User.Drawings")
		(19 "Cmts.User" user "User.Comments")
		(21 "Eco1.User" user "User.Eco1")
		(23 "Eco2.User" user "User.Eco2")
		(25 "Edge.Cuts" user "Board Geometry/Outline")
		(27 "Margin" user)
		(31 "F.CrtYd" user "Package Geometry/Place Bound Top")
		(29 "B.CrtYd" user "Package Geometry/Place Bound Bottom")
		(35 "F.Fab" user "Ref Des/Assembly Top")
		(33 "B.Fab" user "Ref Des/Assembly Bottom")
	)
	(footprint ""
		(layer "F.Cu")
		(at 461.445356 -382.077214)
		(property "Reference" "R2316"
			(at 0 0 0)
			(layer "F.SilkS")
			(hide yes)
			(effects
				(font
					(size 1.27 1.27)
				)
			)
		)
		(property "Value" ""
			(at 0 0 0)
			(layer "F.Fab")
			(effects
				(font
					(size 1.27 1.27)
				)
			)
		)
		(duplicate_pad_numbers_are_jumpers no)
		(fp_line
			(start -0.7874 -0.4064)
			(end 0.7874 -0.4064)
			(stroke
				(width 0.1524)
				(type default)
			)
			(layer "F.SilkS")
		)
		(fp_line
			(start -0.7874 0.4064)
			(end -0.7874 -0.4064)
			(stroke
				(width 0.1524)
				(type default)
			)
			(layer "F.SilkS")
		)
		(fp_line
			(start 0.7874 -0.4064)
			(end 0.7874 0.4064)
			(stroke
				(width 0.1524)
				(type default)
			)
			(layer "F.SilkS")
		)
		(fp_line
			(start 0.7874 0.4064)
			(end -0.7874 0.4064)
			(stroke
				(width 0.1524)
				(type default)
			)
			(layer "F.SilkS")
		)
		(fp_line
			(start -0.67945 -0.305054)
			(end -0.12065 -0.305054)
			(stroke
				(width 0.1)
				(type default)
			)
			(layer "F.Fab")
		)
		(fp_line
			(start -0.67945 0.3048)
			(end -0.67945 -0.305054)
			(stroke
				(width 0.1)
				(type default)
			)
			(layer "F.Fab")
		)
		(fp_line
			(start -0.12065 -0.305054)
			(end -0.12065 -0.2794)
			(stroke
				(width 0.1)
				(type default)
			)
			(layer "F.Fab")
		)
		(fp_line
			(start -0.12065 -0.2794)
			(end 0.12065 -0.2794)
			(stroke
				(width 0.1)
				(type default)
			)
			(layer "F.Fab")
		)
		(fp_line
			(start -0.12065 0.2794)
			(end -0.12065 0.3048)
			(stroke
				(width 0.1)
				(type default)
			)
			(layer "F.Fab")
		)
		(fp_line
			(start -0.12065 0.3048)
			(end -0.67945 0.3048)
			(stroke
				(width 0.1)
				(type default)
			)
			(layer "F.Fab")
		)
		(fp_line
			(start 0.120396 0.2794)
			(end -0.12065 0.2794)
			(stroke
				(width 0.1)
				(type default)
			)
			(layer "F.Fab")
		)
		(fp_line
			(start 0.120396 0.3048)
			(end 0.120396 0.2794)
			(stroke
				(width 0.1)
				(type default)
			)
			(layer "F.Fab")
		)
		(fp_line
			(start 0.12065 -0.3048)
			(end 0.67945 -0.3048)
			(stroke
				(width 0.1)
				(type default)
			)
			(layer "F.Fab")
		)
		(fp_line
			(start 0.12065 -0.2794)
			(end 0.12065 -0.3048)
			(stroke
				(width 0.1)
				(type default)
			)
			(layer "F.Fab")
		)
		(fp_line
			(start 0.67945 -0.3048)
			(end 0.67945 0.3048)
			(stroke
				(width 0.1)
				(type default)
			)
			(layer "F.Fab")
		)
		(fp_line
			(start 0.67945 0.3048)
			(end 0.120396 0.3048)
			(stroke
				(width 0.1)
				(type default)
			)
			(layer "F.Fab")
		)
		(pad "1" smd circle
			(at -0.40005 0)
			(size 0 0)
			(layers "F.Cu" "F.Mask" "F.Paste")
			(net "PWRGD_P5V_AUX_R")
		)
		(pad "2" smd circle
			(at 0.40005 0)
			(size 0 0)
			(layers "F.Cu" "F.Mask" "F.Paste")
			(net "PWRGD_P5V_AUX")
		)
	)
	(footprint ""
		(layer "F.Cu")
		(at 22.010878 -16.099536 90)
		(property "Reference" "C810"
			(at 0 0 90)
			(layer "F.SilkS")
			(hide yes)
			(effects
				(font
					(size 1.27 1.27)
				)
			)
		)
		(property "Value" ""
			(at 0 0 90)
			(layer "F.Fab")
			(effects
				(font
					(size 1.27 1.27)
				)
			)
		)
		(duplicate_pad_numbers_are_jumpers no)
		(fp_line
			(start 0.299974 -0.150114)
			(end 0.299974 0.150114)
			(stroke
				(width 0.1)
				(type default)
			)
			(layer "F.Fab")
		)
		(fp_line
			(start -0.299974 -0.150114)
			(end 0.299974 -0.150114)
			(stroke
				(width 0.1)
				(type default)
			)
			(layer "F.Fab")
		)
		(fp_line
			(start 0.299974 0.150114)
			(end -0.299974 0.150114)
			(stroke
				(width 0.1)
				(type default)
			)
			(layer "F.Fab")
		)
		(fp_line
			(start -0.299974 0.150114)
			(end -0.299974 -0.150114)
			(stroke
				(width 0.1)
				(type default)
			)
			(layer "F.Fab")
		)
		(pad "1" smd rect
			(at -0.2667 0 90)
			(size 0.3048 0.381)
			(layers "F.Cu" "F.Mask" "F.Paste")
			(net "P5E_CPU1_PE1_TX_C_DN<13>")
		)
		(pad "2" smd rect
			(at 0.2667 0 90)
			(size 0.3048 0.381)
			(layers "F.Cu" "F.Mask" "F.Paste")
			(net "P5E_CPU1_PE1_TX_DN<13>")
		)
	)
	(footprint ""
		(layer "F.Cu")
		(at 209.74558 -131.846828 180)
		(property "Reference" "R1689"
			(at 0 0 180)
			(layer "F.SilkS")
			(hide yes)
			(effects
				(font
					(size 1.27 1.27)
				)
			)
		)
		(property "Value" ""
			(at 0 0 180)
			(layer "F.Fab")
			(effects
				(font
					(size 1.27 1.27)
				)
			)
		)
		(duplicate_pad_numbers_are_jumpers no)
		(fp_line
			(start 0.7874 0.4064)
			(end -0.7874 0.4064)
			(stroke
				(width 0.1524)
				(type default)
			)
			(layer "F.SilkS")
		)
		(fp_line
			(start 0.7874 -0.4064)
			(end 0.7874 0.4064)
			(stroke
				(width 0.1524)
				(type default)
			)
			(layer "F.SilkS")
		)
		(fp_line
			(start -0.7874 0.4064)
			(end -0.7874 -0.4064)
			(stroke
				(width 0.1524)
				(type default)
			)
			(layer "F.SilkS")
		)
		(fp_line
			(start -0.7874 -0.4064)
			(end 0.7874 -0.4064)
			(stroke
				(width 0.1524)
				(type default)
			)
			(layer "F.SilkS")
		)
		(fp_line
			(start 0.67945 0.3048)
			(end 0.120396 0.3048)
			(stroke
				(width 0.1)
				(type default)
			)
			(layer "F.Fab")
		)
		(fp_line
			(start 0.67945 -0.3048)
			(end 0.67945 0.3048)
			(stroke
				(width 0.1)
				(type default)
			)
			(layer "F.Fab")
		)
		(fp_line
			(start 0.12065 -0.2794)
			(end 0.12065 -0.3048)
			(stroke
				(width 0.1)
				(type default)
			)
			(layer "F.Fab")
		)
		(fp_line
			(start 0.12065 -0.3048)
			(end 0.67945 -0.3048)
			(stroke
				(width 0.1)
				(type default)
			)
			(layer "F.Fab")
		)
		(fp_line
			(start 0.120396 0.3048)
			(end 0.120396 0.2794)
			(stroke
				(width 0.1)
				(type default)
			)
			(layer "F.Fab")
		)
		(fp_line
			(start 0.120396 0.2794)
			(end -0.12065 0.2794)
			(stroke
				(width 0.1)
				(type default)
			)
			(layer "F.Fab")
		)
		(fp_line
			(start -0.12065 0.3048)
			(end -0.67945 0.3048)
			(stroke
				(width 0.1)
				(type default)
			)
			(layer "F.Fab")
		)
		(fp_line
			(start -0.12065 0.2794)
			(end -0.12065 0.3048)
			(stroke
				(width 0.1)
				(type default)
			)
			(layer "F.Fab")
		)
		(fp_line
			(start -0.12065 -0.2794)
			(end 0.12065 -0.2794)
			(stroke
				(width 0.1)
				(type default)
			)
			(layer "F.Fab")
		)
		(fp_line
			(start -0.12065 -0.305054)
			(end -0.12065 -0.2794)
			(stroke
				(width 0.1)
				(type default)
			)
			(layer "F.Fab")
		)
		(fp_line
			(start -0.67945 0.3048)
			(end -0.67945 -0.305054)
			(stroke
				(width 0.1)
				(type default)
			)
			(layer "F.Fab")
		)
		(fp_line
			(start -0.67945 -0.305054)
			(end -0.12065 -0.305054)
			(stroke
				(width 0.1)
				(type default)
			)
			(layer "F.Fab")
		)
		(pad "1" smd circle
			(at -0.40005 0 180)
			(size 0 0)
			(layers "F.Cu" "F.Mask" "F.Paste")
			(net "FM_COMP_P3V3_AUX_VIN")
		)
		(pad "2" smd circle
			(at 0.40005 0 180)
			(size 0 0)
			(layers "F.Cu" "F.Mask" "F.Paste")
			(net "GND")
		)
	)
)
